(kicad_pcb
	(version 20221018)
	(generator pcbnew)
	(general
    (thickness 1.62)
  )
	(paper "A4")
	(title_block
    (title "ECP5 - Datacenter Secure Control Module (DC-SCM)")
    (date "2024-07-01")
    (rev "1.2.1")
		(comment 9 "footprints 69-77 of 506")
	)
	(layers
    (0 "F.Cu" signal)
    (1 "In1.Cu" power)
    (2 "In2.Cu" signal)
    (3 "In3.Cu" power)
    (4 "In4.Cu" power)
    (5 "In5.Cu" signal)
    (6 "In6.Cu" power)
    (31 "B.Cu" signal)
    (32 "B.Adhes" user "B.Adhesive")
    (33 "F.Adhes" user "F.Adhesive")
    (34 "B.Paste" user)
    (35 "F.Paste" user)
    (36 "B.SilkS" user "B.Silkscreen")
    (37 "F.SilkS" user "F.Silkscreen")
    (38 "B.Mask" user)
    (39 "F.Mask" user)
    (40 "Dwgs.User" user "User.Drawings")
    (41 "Cmts.User" user "User.Comments")
    (42 "Eco1.User" user "User.Eco1")
    (43 "Eco2.User" user "User.Eco2")
    (44 "Edge.Cuts" user)
    (45 "Margin" user)
    (46 "B.CrtYd" user "B.Courtyard")
    (47 "F.CrtYd" user "F.Courtyard")
    (48 "B.Fab" user)
    (49 "F.Fab" user)
  )
	(footprint "antmicro-footprints:R_0402_1005Metric" (layer "F.Cu")
    (at 143.2 167.75 90)
    (descr "Resistor SMD 0402")
    (tags "resistor SMD 0402")
    (property "Author" "Antmicro")
    (property "License" "Apache-2.0")
    (property "MPN" "CR0402-FX-3300GLF")
    (property "Manufacturer" "Bourns")
    (property "Public" "False")
    (property "Sheetfile" "pcie-conn.kicad_sch")
    (property "Sheetname" "PCIe-connector")
    (property "Tolerance" "1%")
    (property "Val" "330R")
    (property "ki_description" "SMD Chip Resistor, 330 ohm, ± 1%, 62.5 mW, 0402 [1005 Metric], Thick Film, General Purpose")
    (property "ki_keywords" "0402, SMT, RESISTOR, PASSIVE")
    (attr smd)
    (fp_text reference "R18" (at 0.005 1.05 90) (layer "F.SilkS")
        (effects (font (size 0.7 0.7) (thickness 0.127)))
    )
    (fp_text value "R_330R_0402" (at 0 1.17 90) (layer "F.Fab")
        (effects (font (size 1 1) (thickness 0.15)))
    )
    (fp_text user "License: Apache-2.0" (at -0.95 5.169 90) (layer "F.Fab") hide
        (effects (font (size 0.7 0.7) (thickness 0.15)) (justify left bottom))
    )
    (fp_text user "Author: Antmicro" (at -0.95 4.169 90) (layer "F.Fab") hide
        (effects (font (size 0.7 0.7) (thickness 0.15)) (justify left bottom))
    )
    (fp_text user "${REFERENCE}" (at 0 0 90) (layer "F.Fab")
        (effects (font (size 0.25 0.25) (thickness 0.04)))
    )
    (fp_rect (start -0.925 -0.47) (end 0.925 0.47)
      (stroke (width 0.05) (type default)) (fill none) (layer "F.CrtYd"))
    (fp_rect (start -0.5 -0.25) (end 0.5 0.25)
      (stroke (width 0.15) (type solid)) (fill none) (layer "F.Fab"))
    (pad "1" smd roundrect (at -0.48 0 90) (size 0.59 0.64) (layers "F.Cu" "F.Paste" "F.Mask") (roundrect_rratio 0.25)
      (net 777 "Net-(D1-A)") (pintype "passive"))
    (pad "2" smd roundrect (at 0.48 0 90) (size 0.59 0.64) (layers "F.Cu" "F.Paste" "F.Mask") (roundrect_rratio 0.25)
      (net 2 "VCC3V3") (pintype "passive"))
  )
	(footprint "antmicro-footprints:C_0402_1005Metric" (layer "F.Cu")
    (at 130.565 168.325 -90)
    (descr "Capacitor SMD 0402")
    (tags "capacitor SMD 0402")
    (property "Author" "Antmicro")
    (property "Dielectric" "X5R")
    (property "License" "Apache-2.0")
    (property "MPN" "GRM155R61H104KE14D")
    (property "Manufacturer" "Murata")
    (property "Public" "False")
    (property "Sheetfile" "pcie-conn.kicad_sch")
    (property "Sheetname" "PCIe-connector")
    (property "Val" "100n")
    (property "Voltage" "50V")
    (property "ki_description" "SMD Multilayer Ceramic Capacitor, 0.1 µF, 50 V, 0402 [1005 Metric], ± 10%, X5R, GRM Series")
    (property "ki_keywords" "0402, SMT, CAPACITOR, PASSIVE, CERAMIC, MLCC")
    (attr smd)
    (fp_text reference "C36" (at 2.11 -0.08 90) (layer "F.SilkS")
        (effects (font (size 0.7 0.7) (thickness 0.127)))
    )
    (fp_text value "C_100n_0402" (at 0 1.17 90) (layer "F.Fab")
        (effects (font (size 1 1) (thickness 0.15)))
    )
    (fp_text user "License: Apache-2.0" (at -0.939 5.799 -90) (layer "F.Fab") hide
        (effects (font (size 0.7 0.7) (thickness 0.15)) (justify left bottom))
    )
    (fp_text user "${REFERENCE}" (at 0 0 90) (layer "F.Fab")
        (effects (font (size 0.25 0.25) (thickness 0.04)))
    )
    (fp_text user "Author: Antmicro" (at -0.939 3.399 -90) (layer "F.Fab") hide
        (effects (font (size 0.7 0.7) (thickness 0.15)) (justify left bottom))
    )
    (fp_rect (start -0.925 -0.47) (end 0.925 0.47)
      (stroke (width 0.05) (type default)) (fill none) (layer "F.CrtYd"))
    (fp_line (start -0.494 -0.25) (end 0.504 -0.25)
      (stroke (width 0.15) (type solid)) (layer "F.Fab"))
    (fp_line (start -0.494 0.248) (end -0.494 -0.25)
      (stroke (width 0.15) (type solid)) (layer "F.Fab"))
    (fp_line (start 0.504 -0.25) (end 0.504 0.248)
      (stroke (width 0.15) (type solid)) (layer "F.Fab"))
    (fp_line (start 0.504 0.248) (end -0.494 0.248)
      (stroke (width 0.15) (type solid)) (layer "F.Fab"))
    (pad "1" smd roundrect (at -0.48 0 270) (size 0.59 0.64) (layers "F.Cu" "F.Paste" "F.Mask") (roundrect_rratio 0.25)
      (net 214 "Net-(J2-PET1_N)") (pintype "passive"))
    (pad "2" smd roundrect (at 0.48 0 270) (size 0.59 0.64) (layers "F.Cu" "F.Paste" "F.Mask") (roundrect_rratio 0.25)
      (net 693 "PCIE_HPM_TX1_N") (pintype "passive"))
  )
	(footprint "antmicro-footprints:C_0402_1005Metric" (layer "F.Cu")
    (at 129.565 168.325 -90)
    (descr "Capacitor SMD 0402")
    (tags "capacitor SMD 0402")
    (property "Author" "Antmicro")
    (property "Dielectric" "X5R")
    (property "License" "Apache-2.0")
    (property "MPN" "GRM155R61H104KE14D")
    (property "Manufacturer" "Murata")
    (property "Public" "False")
    (property "Sheetfile" "pcie-conn.kicad_sch")
    (property "Sheetname" "PCIe-connector")
    (property "Val" "100n")
    (property "Voltage" "50V")
    (property "ki_description" "SMD Multilayer Ceramic Capacitor, 0.1 µF, 50 V, 0402 [1005 Metric], ± 10%, X5R, GRM Series")
    (property "ki_keywords" "0402, SMT, CAPACITOR, PASSIVE, CERAMIC, MLCC")
    (attr smd)
    (fp_text reference "C32" (at 2.14 0.01 90) (layer "F.SilkS")
        (effects (font (size 0.7 0.7) (thickness 0.127)))
    )
    (fp_text value "C_100n_0402" (at 0 1.17 90) (layer "F.Fab")
        (effects (font (size 1 1) (thickness 0.15)))
    )
    (fp_text user "Author: Antmicro" (at -0.939 3.399 -90) (layer "F.Fab") hide
        (effects (font (size 0.7 0.7) (thickness 0.15)) (justify left bottom))
    )
    (fp_text user "License: Apache-2.0" (at -0.939 5.799 -90) (layer "F.Fab") hide
        (effects (font (size 0.7 0.7) (thickness 0.15)) (justify left bottom))
    )
    (fp_text user "${REFERENCE}" (at 0 0 90) (layer "F.Fab")
        (effects (font (size 0.25 0.25) (thickness 0.04)))
    )
    (fp_rect (start -0.925 -0.47) (end 0.925 0.47)
      (stroke (width 0.05) (type default)) (fill none) (layer "F.CrtYd"))
    (fp_line (start -0.494 -0.25) (end 0.504 -0.25)
      (stroke (width 0.15) (type solid)) (layer "F.Fab"))
    (fp_line (start -0.494 0.248) (end -0.494 -0.25)
      (stroke (width 0.15) (type solid)) (layer "F.Fab"))
    (fp_line (start 0.504 -0.25) (end 0.504 0.248)
      (stroke (width 0.15) (type solid)) (layer "F.Fab"))
    (fp_line (start 0.504 0.248) (end -0.494 0.248)
      (stroke (width 0.15) (type solid)) (layer "F.Fab"))
    (pad "1" smd roundrect (at -0.48 0 270) (size 0.59 0.64) (layers "F.Cu" "F.Paste" "F.Mask") (roundrect_rratio 0.25)
      (net 17 "Net-(J2-PET1_P)") (pintype "passive"))
    (pad "2" smd roundrect (at 0.48 0 270) (size 0.59 0.64) (layers "F.Cu" "F.Paste" "F.Mask") (roundrect_rratio 0.25)
      (net 689 "PCIE_HPM_TX1_P") (pintype "passive"))
  )
	(footprint "antmicro-footprints:R_0402_1005Metric" (layer "F.Cu")
    (at 127.1 154.3 -90)
    (descr "Resistor SMD 0402")
    (tags "resistor SMD 0402")
    (property "Author" "Antmicro")
    (property "License" "Apache-2.0")
    (property "MPN" "CR0402-FX-1002GLF")
    (property "Manufacturer" "Bourns")
    (property "Public" "False")
    (property "Sheetfile" "pcie-conn.kicad_sch")
    (property "Sheetname" "PCIe-connector")
    (property "Tolerance" "1%")
    (property "Val" "10k")
    (property "ki_description" "SMD Chip Resistor, 10 kohm, ± 1%, 62.5 mW, 0402 [1005 Metric], Thick Film, General Purpose")
    (property "ki_keywords" "0402, SMT, RESISTOR, PASSIVE")
    (attr smd)
    (fp_text reference "R19" (at -2.75 0.08 90) (layer "F.SilkS")
        (effects (font (size 0.7 0.7) (thickness 0.127)))
    )
    (fp_text value "R_10k_0402" (at 0 1.17 90) (layer "F.Fab")
        (effects (font (size 1 1) (thickness 0.15)))
    )
    (fp_text user "${REFERENCE}" (at 0 0 90) (layer "F.Fab")
        (effects (font (size 0.25 0.25) (thickness 0.04)))
    )
    (fp_text user "License: Apache-2.0" (at -0.95 5.169 -90) (layer "F.Fab") hide
        (effects (font (size 0.7 0.7) (thickness 0.15)) (justify left bottom))
    )
    (fp_text user "Author: Antmicro" (at -0.95 4.169 -90) (layer "F.Fab") hide
        (effects (font (size 0.7 0.7) (thickness 0.15)) (justify left bottom))
    )
    (fp_rect (start -0.925 -0.47) (end 0.925 0.47)
      (stroke (width 0.05) (type default)) (fill none) (layer "F.CrtYd"))
    (fp_rect (start -0.5 -0.25) (end 0.5 0.25)
      (stroke (width 0.15) (type solid)) (fill none) (layer "F.Fab"))
    (pad "1" smd roundrect (at -0.48 0 270) (size 0.59 0.64) (layers "F.Cu" "F.Paste" "F.Mask") (roundrect_rratio 0.25)
      (net 2 "VCC3V3") (pintype "passive"))
    (pad "2" smd roundrect (at 0.48 0 270) (size 0.59 0.64) (layers "F.Cu" "F.Paste" "F.Mask") (roundrect_rratio 0.25)
      (net 58 "PRSNT0_N") (pintype "passive"))
  )
	(footprint "antmicro-footprints:C_0402_1005Metric" (layer "F.Cu")
    (at 121.05 154.8 -90)
    (descr "Capacitor SMD 0402")
    (tags "capacitor SMD 0402")
    (property "Author" "Antmicro")
    (property "Dielectric" "")
    (property "License" "Apache-2.0")
    (property "MPN" "CC0402MRX5R5BB106")
    (property "Manufacturer" "YAGEO")
    (property "Public" "False")
    (property "Sheetfile" "pcie-conn.kicad_sch")
    (property "Sheetname" "PCIe-connector")
    (property "Val" "10u")
    (property "Voltage" "")
    (property "ki_description" "SMD Multilayer Ceramic Capacitor, 10 µF, 6.3 V, 0402 [1005 Metric], ± 20%, X5R, CC Series")
    (property "ki_keywords" "0402, SMT, CAPACITOR, PASSIVE, MLCC, CERAMIC")
    (attr smd)
    (fp_text reference "C40" (at 0.04 1.22 90) (layer "F.SilkS")
        (effects (font (size 0.7 0.7) (thickness 0.127)))
    )
    (fp_text value "C_10u_0402" (at 0 1.17 90) (layer "F.Fab")
        (effects (font (size 1 1) (thickness 0.15)))
    )
    (fp_text user "${REFERENCE}" (at 0 0 90) (layer "F.Fab")
        (effects (font (size 0.25 0.25) (thickness 0.04)))
    )
    (fp_text user "Author: Antmicro" (at -0.939 3.399 -90) (layer "F.Fab") hide
        (effects (font (size 0.7 0.7) (thickness 0.15)) (justify left bottom))
    )
    (fp_text user "License: Apache-2.0" (at -0.939 5.799 -90) (layer "F.Fab") hide
        (effects (font (size 0.7 0.7) (thickness 0.15)) (justify left bottom))
    )
    (fp_rect (start -0.925 -0.47) (end 0.925 0.47)
      (stroke (width 0.05) (type default)) (fill none) (layer "F.CrtYd"))
    (fp_line (start -0.494 -0.25) (end 0.504 -0.25)
      (stroke (width 0.15) (type solid)) (layer "F.Fab"))
    (fp_line (start -0.494 0.248) (end -0.494 -0.25)
      (stroke (width 0.15) (type solid)) (layer "F.Fab"))
    (fp_line (start 0.504 -0.25) (end 0.504 0.248)
      (stroke (width 0.15) (type solid)) (layer "F.Fab"))
    (fp_line (start 0.504 0.248) (end -0.494 0.248)
      (stroke (width 0.15) (type solid)) (layer "F.Fab"))
    (pad "1" smd roundrect (at -0.48 0 270) (size 0.59 0.64) (layers "F.Cu" "F.Paste" "F.Mask") (roundrect_rratio 0.25)
      (net 1 "GND") (pintype "passive"))
    (pad "2" smd roundrect (at 0.48 0 270) (size 0.59 0.64) (layers "F.Cu" "F.Paste" "F.Mask") (roundrect_rratio 0.25)
      (net 2 "VCC3V3") (pintype "passive"))
  )
	(footprint "antmicro-footprints:C_0402_1005Metric" (layer "F.Cu")
    (at 126.575 168.325 -90)
    (descr "Capacitor SMD 0402")
    (tags "capacitor SMD 0402")
    (property "Author" "Antmicro")
    (property "Dielectric" "X5R")
    (property "License" "Apache-2.0")
    (property "MPN" "GRM155R61H104KE14D")
    (property "Manufacturer" "Murata")
    (property "Public" "False")
    (property "Sheetfile" "pcie-conn.kicad_sch")
    (property "Sheetname" "PCIe-connector")
    (property "Val" "100n")
    (property "Voltage" "50V")
    (property "ki_description" "SMD Multilayer Ceramic Capacitor, 0.1 µF, 50 V, 0402 [1005 Metric], ± 10%, X5R, GRM Series")
    (property "ki_keywords" "0402, SMT, CAPACITOR, PASSIVE, CERAMIC, MLCC")
    (attr smd)
    (fp_text reference "C31" (at 2.11 0.01 90) (layer "F.SilkS")
        (effects (font (size 0.7 0.7) (thickness 0.127)))
    )
    (fp_text value "C_100n_0402" (at 0 1.17 90) (layer "F.Fab")
        (effects (font (size 1 1) (thickness 0.15)))
    )
    (fp_text user "Author: Antmicro" (at -0.939 3.399 -90) (layer "F.Fab") hide
        (effects (font (size 0.7 0.7) (thickness 0.15)) (justify left bottom))
    )
    (fp_text user "${REFERENCE}" (at 0 0 90) (layer "F.Fab")
        (effects (font (size 0.25 0.25) (thickness 0.04)))
    )
    (fp_text user "License: Apache-2.0" (at -0.939 5.799 -90) (layer "F.Fab") hide
        (effects (font (size 0.7 0.7) (thickness 0.15)) (justify left bottom))
    )
    (fp_rect (start -0.925 -0.47) (end 0.925 0.47)
      (stroke (width 0.05) (type default)) (fill none) (layer "F.CrtYd"))
    (fp_line (start -0.494 -0.25) (end 0.504 -0.25)
      (stroke (width 0.15) (type solid)) (layer "F.Fab"))
    (fp_line (start -0.494 0.248) (end -0.494 -0.25)
      (stroke (width 0.15) (type solid)) (layer "F.Fab"))
    (fp_line (start 0.504 -0.25) (end 0.504 0.248)
      (stroke (width 0.15) (type solid)) (layer "F.Fab"))
    (fp_line (start 0.504 0.248) (end -0.494 0.248)
      (stroke (width 0.15) (type solid)) (layer "F.Fab"))
    (pad "1" smd roundrect (at -0.48 0 270) (size 0.59 0.64) (layers "F.Cu" "F.Paste" "F.Mask") (roundrect_rratio 0.25)
      (net 16 "Net-(J2-PET0_P)") (pintype "passive"))
    (pad "2" smd roundrect (at 0.48 0 270) (size 0.59 0.64) (layers "F.Cu" "F.Paste" "F.Mask") (roundrect_rratio 0.25)
      (net 688 "PCIE_HPM_TX0_P") (pintype "passive"))
  )
	(footprint "antmicro-footprints:C_0402_1005Metric" (layer "F.Cu")
    (at 134.7 154.9 -90)
    (descr "Capacitor SMD 0402")
    (tags "capacitor SMD 0402")
    (property "Author" "Antmicro")
    (property "Dielectric" "")
    (property "License" "Apache-2.0")
    (property "MPN" "CC0402MRX5R5BB106")
    (property "Manufacturer" "YAGEO")
    (property "Public" "False")
    (property "Sheetfile" "pcie-conn.kicad_sch")
    (property "Sheetname" "PCIe-connector")
    (property "Val" "10u")
    (property "Voltage" "")
    (property "ki_description" "SMD Multilayer Ceramic Capacitor, 10 µF, 6.3 V, 0402 [1005 Metric], ± 20%, X5R, CC Series")
    (property "ki_keywords" "0402, SMT, CAPACITOR, PASSIVE, MLCC, CERAMIC")
    (attr smd)
    (fp_text reference "C42" (at -2.495 -0.01 90) (layer "F.SilkS")
        (effects (font (size 0.7 0.7) (thickness 0.127)))
    )
    (fp_text value "C_10u_0402" (at 0 1.17 90) (layer "F.Fab")
        (effects (font (size 1 1) (thickness 0.15)))
    )
    (fp_text user "Author: Antmicro" (at -0.939 3.399 -90) (layer "F.Fab") hide
        (effects (font (size 0.7 0.7) (thickness 0.15)) (justify left bottom))
    )
    (fp_text user "License: Apache-2.0" (at -0.939 5.799 -90) (layer "F.Fab") hide
        (effects (font (size 0.7 0.7) (thickness 0.15)) (justify left bottom))
    )
    (fp_text user "${REFERENCE}" (at 0 0 90) (layer "F.Fab")
        (effects (font (size 0.25 0.25) (thickness 0.04)))
    )
    (fp_rect (start -0.925 -0.47) (end 0.925 0.47)
      (stroke (width 0.05) (type default)) (fill none) (layer "F.CrtYd"))
    (fp_line (start -0.494 -0.25) (end 0.504 -0.25)
      (stroke (width 0.15) (type solid)) (layer "F.Fab"))
    (fp_line (start -0.494 0.248) (end -0.494 -0.25)
      (stroke (width 0.15) (type solid)) (layer "F.Fab"))
    (fp_line (start 0.504 -0.25) (end 0.504 0.248)
      (stroke (width 0.15) (type solid)) (layer "F.Fab"))
    (fp_line (start 0.504 0.248) (end -0.494 0.248)
      (stroke (width 0.15) (type solid)) (layer "F.Fab"))
    (pad "1" smd roundrect (at -0.48 0 270) (size 0.59 0.64) (layers "F.Cu" "F.Paste" "F.Mask") (roundrect_rratio 0.25)
      (net 1 "GND") (pintype "passive"))
    (pad "2" smd roundrect (at 0.48 0 270) (size 0.59 0.64) (layers "F.Cu" "F.Paste" "F.Mask") (roundrect_rratio 0.25)
      (net 2 "VCC3V3") (pintype "passive"))
  )
	(footprint "antmicro-footprints:R_0402_1005Metric" (layer "F.Cu")
    (at 128.1 154.3 90)
    (descr "Resistor SMD 0402")
    (tags "resistor SMD 0402")
    (property "Author" "Antmicro")
    (property "License" "Apache-2.0")
    (property "MPN" "CR0402-FX-1002GLF")
    (property "Manufacturer" "Bourns")
    (property "Public" "False")
    (property "Sheetfile" "pcie-conn.kicad_sch")
    (property "Sheetname" "PCIe-connector")
    (property "Tolerance" "1%")
    (property "Val" "10k")
    (property "ki_description" "SMD Chip Resistor, 10 kohm, ± 1%, 62.5 mW, 0402 [1005 Metric], Thick Film, General Purpose")
    (property "ki_keywords" "0402, SMT, RESISTOR, PASSIVE")
    (attr smd)
    (fp_text reference "R20" (at 2.735 0.05 90) (layer "F.SilkS")
        (effects (font (size 0.7 0.7) (thickness 0.127)))
    )
    (fp_text value "R_10k_0402" (at -0.2 1.1 90) (layer "F.Fab")
        (effects (font (size 1 1) (thickness 0.15)))
    )
    (fp_text user "Author: Antmicro" (at -0.95 4.169 90) (layer "F.Fab") hide
        (effects (font (size 0.7 0.7) (thickness 0.15)) (justify left bottom))
    )
    (fp_text user "License: Apache-2.0" (at -0.95 5.169 90) (layer "F.Fab") hide
        (effects (font (size 0.7 0.7) (thickness 0.15)) (justify left bottom))
    )
    (fp_text user "${REFERENCE}" (at 0 0 90) (layer "F.Fab")
        (effects (font (size 0.25 0.25) (thickness 0.04)))
    )
    (fp_rect (start -0.925 -0.47) (end 0.925 0.47)
      (stroke (width 0.05) (type default)) (fill none) (layer "F.CrtYd"))
    (fp_rect (start -0.5 -0.25) (end 0.5 0.25)
      (stroke (width 0.15) (type solid)) (fill none) (layer "F.Fab"))
    (pad "1" smd roundrect (at -0.48 0 90) (size 0.59 0.64) (layers "F.Cu" "F.Paste" "F.Mask") (roundrect_rratio 0.25)
      (net 376 "Net-(J2-ALERT)") (pintype "passive"))
    (pad "2" smd roundrect (at 0.48 0 90) (size 0.59 0.64) (layers "F.Cu" "F.Paste" "F.Mask") (roundrect_rratio 0.25)
      (net 218 "VCC1V8") (pintype "passive"))
  )
	(footprint "antmicro-footprints:C_0402_1005Metric" (layer "F.Cu")
    (at 133.535 168.325 -90)
    (descr "Capacitor SMD 0402")
    (tags "capacitor SMD 0402")
    (property "Author" "Antmicro")
    (property "Dielectric" "X5R")
    (property "License" "Apache-2.0")
    (property "MPN" "GRM155R61H104KE14D")
    (property "Manufacturer" "Murata")
    (property "Public" "False")
    (property "Sheetfile" "pcie-conn.kicad_sch")
    (property "Sheetname" "PCIe-connector")
    (property "Val" "100n")
    (property "Voltage" "50V")
    (property "ki_description" "SMD Multilayer Ceramic Capacitor, 0.1 µF, 50 V, 0402 [1005 Metric], ± 10%, X5R, GRM Series")
    (property "ki_keywords" "0402, SMT, CAPACITOR, PASSIVE, CERAMIC, MLCC")
    (attr smd)
    (fp_text reference "C37" (at 2.14 -0.13 90) (layer "F.SilkS")
        (effects (font (size 0.7 0.7) (thickness 0.127)))
    )
    (fp_text value "C_100n_0402" (at 0 1.17 90) (layer "F.Fab")
        (effects (font (size 1 1) (thickness 0.15)))
    )
    (fp_text user "Author: Antmicro" (at -0.939 3.399 -90) (layer "F.Fab") hide
        (effects (font (size 0.7 0.7) (thickness 0.15)) (justify left bottom))
    )
    (fp_text user "License: Apache-2.0" (at -0.939 5.799 -90) (layer "F.Fab") hide
        (effects (font (size 0.7 0.7) (thickness 0.15)) (justify left bottom))
    )
    (fp_text user "${REFERENCE}" (at 0 0 90) (layer "F.Fab")
        (effects (font (size 0.25 0.25) (thickness 0.04)))
    )
    (fp_rect (start -0.925 -0.47) (end 0.925 0.47)
      (stroke (width 0.05) (type default)) (fill none) (layer "F.CrtYd"))
    (fp_line (start -0.494 -0.25) (end 0.504 -0.25)
      (stroke (width 0.15) (type solid)) (layer "F.Fab"))
    (fp_line (start -0.494 0.248) (end -0.494 -0.25)
      (stroke (width 0.15) (type solid)) (layer "F.Fab"))
    (fp_line (start 0.504 -0.25) (end 0.504 0.248)
      (stroke (width 0.15) (type solid)) (layer "F.Fab"))
    (fp_line (start 0.504 0.248) (end -0.494 0.248)
      (stroke (width 0.15) (type solid)) (layer "F.Fab"))
    (pad "1" smd roundrect (at -0.48 0 270) (size 0.59 0.64) (layers "F.Cu" "F.Paste" "F.Mask") (roundrect_rratio 0.25)
      (net 215 "Net-(J2-PET2_N)") (pintype "passive"))
    (pad "2" smd roundrect (at 0.48 0 270) (size 0.59 0.64) (layers "F.Cu" "F.Paste" "F.Mask") (roundrect_rratio 0.25)
      (net 694 "PCIE_HPM_TX2_N") (pintype "passive"))
  )
)
